# BASEBOARD_FAB2 (Tioga Pass) — schematic netlist excerpt (pin names and nets, part order shuffled) for the footprints in the layout excerpt that follows; sources: Cadence DE-HDL packaged netlist, KiCad conversion of Wiwynn_Tioga_Pass_MB.brd

J9L1  SCONN288_H44441003  SCONN  pkg PIP  page 88
  \12v\(1)  = P12V_NVDIMM_KLM
  VSS(93)  = GND
  DQ(4)  = M_M_DQ<4>
  VSS(92)  = GND
  DQ(0)  = M_M_DQ<0>
  VSS(91)  = GND
  DQS9P  = M_M_DQS_DP<9>
  DQS9N  = M_M_DQS_DN<9>
  VSS(90)  = GND
  DQ(6)  = M_M_DQ<6>
  VSS(89)  = GND
  DQ(2)  = M_M_DQ<2>
  VSS(88)  = GND
  DQ(12)  = M_M_DQ<12>
  VSS(87)  = GND
  DQ(8)  = M_M_DQ<8>
  VSS(86)  = GND
  DQS10P  = M_M_DQS_DP<10>
  DQS10N  = M_M_DQS_DN<10>
  VSS(85)  = GND
  DQ(14)  = M_M_DQ<14>
  VSS(84)  = GND
  DQ(10)  = M_M_DQ<10>
  VSS(83)  = GND
  DQ(20)  = M_M_DQ<20>
  VSS(82)  = GND
  DQ(16)  = M_M_DQ<16>
  VSS(81)  = GND
  DQS11P  = M_M_DQS_DP<11>
  DQS11N  = M_M_DQS_DN<11>
  VSS(80)  = GND
  DQ(22)  = M_M_DQ<22>
  VSS(79)  = GND
  DQ(18)  = M_M_DQ<18>
  VSS(78)  = GND
  DQ(28)  = M_M_DQ<28>
  VSS(77)  = GND
  DQ(24)  = M_M_DQ<24>
  VSS(76)  = GND
  DQS12P  = M_M_DQS_DP<12>
  DQS12N  = M_M_DQS_DN<12>
  VSS(75)  = GND
  DQ(30)  = M_M_DQ<30>
  VSS(74)  = GND
  DQ(26)  = M_M_DQ<26>
  VSS(73)  = GND
  CB(4)  = M_M_ECC<4>
  VSS(72)  = GND
  CB(0)  = M_M_ECC<0>
  VSS(71)  = GND
  DQS17P  = M_M_DQS_DP<17>
  DQS17N  = M_M_DQS_DN<17>
  VSS(70)  = GND
  CB(6)  = M_M_ECC<6>
  VSS(69)  = GND
  CB(2)  = M_M_ECC<2>
  VSS(68)  = GND
  RESET_N  = M_KLM_RST_N
  VDD(25)  = PVDDQ_KLM
  CKE(0)  = M_M_CKE<2>
  VDD(24)  = PVDDQ_KLM
  ACT_N  = M_M_ACT_N
  BG(0)  = M_M_BG<0>
  VDD(23)  = PVDDQ_KLM
  A12  = M_M_MA<12>
  A9  = M_M_MA<9>
  VDD(22)  = PVDDQ_KLM
  A8  = M_M_MA<8>
  A6  = M_M_MA<6>
  VDD(21)  = PVDDQ_KLM
  A3  = M_M_MA<3>
  A1  = M_M_MA<1>
  VDD(20)  = PVDDQ_KLM
  CK0P  = M_M_CLK_DP<2>
  CK0N  = M_M_CLK_DN<2>
  VDD(19)  = PVDDQ_KLM
  VTT(1)  = PVTT_KLM
  EVENT_N  = FM_DIMM_EVENT_COD_N
  A0  = M_M_MA<0>
  VDD(18)  = PVDDQ_KLM
  BA(0)  = M_M_BA<0>
  A16_RAS_N  = M_M_MA<16>
  VDD(17)  = PVDDQ_KLM
  S0_N  = M_M_CS_N<4>
  VDD(16)  = PVDDQ_KLM
  A15_CAS_N  = M_M_MA<15>
  ODT(0)  = M_M_ODT<2>
  VDD(15)  = PVDDQ_KLM
  S1_N  = M_M_CS_N<5>
  VDD(14)  = PVDDQ_KLM
  ODT(1)  = M_M_ODT<3>
  VDD(13)  = PVDDQ_KLM
  S2_N_C(0)  = M_M_CS_N<6>
  VSS(67)  = GND
  DQ(36)  = M_M_DQ<36>
  VSS(66)  = GND
  DQ(32)  = M_M_DQ<32>
  VSS(65)  = GND
  DQS13P  = M_M_DQS_DP<13>
  DQS13N  = M_M_DQS_DN<13>
  VSS(64)  = GND
  DQ(38)  = M_M_DQ<38>
  VSS(63)  = GND
  DQ(34)  = M_M_DQ<34>
  VSS(62)  = GND
  DQ(44)  = M_M_DQ<44>
  VSS(61)  = GND
  DQ(40)  = M_M_DQ<40>
  VSS(60)  = GND
  DQS14P  = M_M_DQS_DP<14>
  DQS14N  = M_M_DQS_DN<14>
  VSS(59)  = GND
  DQ(46)  = M_M_DQ<46>
  VSS(58)  = GND
  DQ(42)  = M_M_DQ<42>
  VSS(57)  = GND
  DQ(52)  = M_M_DQ<52>
  VSS(56)  = GND
  DQ(48)  = M_M_DQ<48>
  VSS(55)  = GND
  DQS15P  = M_M_DQS_DP<15>
  DQS15N  = M_M_DQS_DN<15>
  VSS(54)  = GND
  DQ(54)  = M_M_DQ<54>
  VSS(53)  = GND
  DQ(50)  = M_M_DQ<50>
  VSS(52)  = GND
  DQ(60)  = M_M_DQ<60>
  VSS(51)  = GND
  DQ(56)  = M_M_DQ<56>
  VSS(50)  = GND
  DQS16P  = M_M_DQS_DP<16>
  DQS16N  = M_M_DQS_DN<16>
  VSS(49)  = GND
  DQ(62)  = M_M_DQ<62>
  VSS(48)  = GND
  DQ(58)  = M_M_DQ<58>
  VSS(47)  = GND
  SA(0)  = PVPP_KLM
  SA(1)  = GND
  SCL  = SMB_DDR_KLM_VPP_SCL
  VPP(4)  = PVPP_KLM
  VPP(3)  = PVPP_KLM
  RFU(2)  = TP_CH_M_DIMM_M1_RFU_2
  \12v\(0)  = P12V_NVDIMM_KLM
  VREFCA  = M_M_VREF
  VSS(46)  = GND
  DQ(5)  = M_M_DQ<5>
  VSS(45)  = GND
  DQ(1)  = M_M_DQ<1>
  VSS(44)  = GND
  DQS0N  = M_M_DQS_DN<0>
  DQS0P  = M_M_DQS_DP<0>
  VSS(43)  = GND
  DQ(7)  = M_M_DQ<7>
  VSS(42)  = GND
  DQ(3)  = M_M_DQ<3>
  VSS(41)  = GND
  DQ(13)  = M_M_DQ<13>
  VSS(40)  = GND
  DQ(9)  = M_M_DQ<9>
  VSS(39)  = GND
  DQS1N  = M_M_DQS_DN<1>
  DQS1P  = M_M_DQS_DP<1>
  VSS(38)  = GND
  DQ(15)  = M_M_DQ<15>
  VSS(37)  = GND
  DQ(11)  = M_M_DQ<11>
  VSS(36)  = GND
  DQ(21)  = M_M_DQ<21>
  VSS(35)  = GND
  DQ(17)  = M_M_DQ<17>
  VSS(34)  = GND
  DQS2N  = M_M_DQS_DN<2>
  DQS2P  = M_M_DQS_DP<2>
  VSS(33)  = GND
  DQ(23)  = M_M_DQ<23>
  VSS(32)  = GND
  DQ(19)  = M_M_DQ<19>
  VSS(31)  = GND
  DQ(29)  = M_M_DQ<29>
  VSS(30)  = GND
  DQ(25)  = M_M_DQ<25>
  VSS(29)  = GND
  DQS3N  = M_M_DQS_DN<3>
  DQS3P  = M_M_DQS_DP<3>
  VSS(28)  = GND
  DQ(31)  = M_M_DQ<31>
  VSS(27)  = GND
  DQ(27)  = M_M_DQ<27>
  VSS(26)  = GND
  CB(5)  = M_M_ECC<5>
  VSS(25)  = GND
  CB(1)  = M_M_ECC<1>
  VSS(24)  = GND
  DQS8N  = M_M_DQS_DN<8>
  DQS8P  = M_M_DQS_DP<8>
  VSS(23)  = GND
  CB(7)  = M_M_ECC<7>
  VSS(22)  = GND
  CB(3)  = M_M_ECC<3>
  VSS(21)  = GND
  CKE(1)  = M_M_CKE<3>
  VDD(12)  = PVDDQ_KLM
  RFU(0)  = TP_CH_M_DIMM_M1_RFU_0
  VDD(11)  = PVDDQ_KLM
  BG(1)  = M_M_BG<1>
  ALERT_N  = M_M_ALERT_N
  VDD(10)  = PVDDQ_KLM
  A11  = M_M_MA<11>
  A7  = M_M_MA<7>
  VDD(9)  = PVDDQ_KLM
  A5  = M_M_MA<5>
  A4  = M_M_MA<4>
  VDD(8)  = PVDDQ_KLM
  A2  = M_M_MA<2>
  VDD(7)  = PVDDQ_KLM
  CK1P  = M_M_CLK_DP<3>
  CK1N  = M_M_CLK_DN<3>
  VDD(6)  = PVDDQ_KLM
  VTT(0)  = PVTT_KLM
  PAR  = M_M_PAR
  VDD(5)  = PVDDQ_KLM
  BA(1)  = M_M_BA<1>
  A10  = M_M_MA<10>
  VDD(4)  = PVDDQ_KLM
  RFU(1)  = TP_CH_M_DIMM_M1_RFU_1
  A14_WE_N  = M_M_MA<14>
  VDD(3)  = PVDDQ_KLM
  SAVE_N_NC  = FM_ADR_COMPLETE_KLM_N
  VDD(2)  = PVDDQ_KLM
  A13  = M_M_MA<13>
  VDD(1)  = PVDDQ_KLM
  A17  = M_M_MA<17>
  C(2)  = M_M_C<2>
  VDD(0)  = PVDDQ_KLM
  S3_N_C(1)  = M_M_CS_N<7>
  SA(2)  = PVPP_KLM
  VSS(20)  = GND
  DQ(37)  = M_M_DQ<37>
  VSS(19)  = GND
  DQ(33)  = M_M_DQ<33>
  VSS(18)  = GND
  DQS4N  = M_M_DQS_DN<4>
  DQS4P  = M_M_DQS_DP<4>
  VSS(17)  = GND
  DQ(39)  = M_M_DQ<39>
  VSS(16)  = GND
  DQ(35)  = M_M_DQ<35>
  VSS(15)  = GND
  DQ(45)  = M_M_DQ<45>
  VSS(14)  = GND
  DQ(41)  = M_M_DQ<41>
  VSS(13)  = GND
  DQS5N  = M_M_DQS_DN<5>
  DQS5P  = M_M_DQS_DP<5>
  VSS(12)  = GND
  DQ(47)  = M_M_DQ<47>
  VSS(11)  = GND
  DQ(43)  = M_M_DQ<43>
  VSS(10)  = GND
  DQ(53)  = M_M_DQ<53>
  VSS(9)  = GND
  DQ(49)  = M_M_DQ<49>
  VSS(8)  = GND
  DQS6N  = M_M_DQS_DN<6>
  DQS6P  = M_M_DQS_DP<6>
  VSS(7)  = GND
  DQ(55)  = M_M_DQ<55>
  VSS(6)  = GND
  DQ(51)  = M_M_DQ<51>
  VSS(5)  = GND
  DQ(61)  = M_M_DQ<61>
  VSS(4)  = GND
  DQ(57)  = M_M_DQ<57>
  VSS(3)  = GND
  DQS7N  = M_M_DQS_DN<7>
  DQS7P  = M_M_DQS_DP<7>
  VSS(2)  = GND
  DQ(63)  = M_M_DQ<63>
  VSS(1)  = GND
  DQ(59)  = M_M_DQ<59>
  VSS(0)  = GND
  VDDSPD  = PVPP_KLM
  SDA  = SMB_DDR_KLM_VPP_SDA
  VPP(1)  = PVPP_KLM
  VPP(0)  = PVPP_KLM
  VPP(2)  = PVPP_KLM

(kicad_pcb
	(version 20260206)
	(generator "pcbnew")
	(generator_version "10.0")
	(general
		(thickness 1.6)
		(legacy_teardrops no)
	)
	(paper "A4")
	(title_block
		(title "Wiwynn_Tioga_Pass_MB.brd")
		(comment 1 "Tioga Pass / footprint 2717 of 4770 (J9L1), pads 202-249 of 291")
	)
	(layers
		(0 "F.Cu" signal "TOP")
		(4 "In1.Cu" signal "L2GND")
		(6 "In2.Cu" signal "L3")
		(8 "In3.Cu" signal "L4GND")
		(10 "In4.Cu" signal "L5")
		(12 "In5.Cu" signal "L6GND")
		(14 "In6.Cu" signal "L7VCC")
		(16 "In7.Cu" signal "L8VCC")
		(18 "In8.Cu" signal "L9GND")
		(20 "In9.Cu" signal "L10")
		(22 "In10.Cu" signal "L11GND")
		(24 "In11.Cu" signal "L12")
		(26 "In12.Cu" signal "L13GND")
		(2 "B.Cu" signal "BOTTOM")
		(9 "F.Adhes" user "F.Adhesive")
		(11 "B.Adhes" user "B.Adhesive")
		(13 "F.Paste" user "Package Geometry/Pastemask Top")
		(15 "B.Paste" user "Package Geometry/Pastemask Bottom")
		(5 "F.SilkS" user "Ref Des/Silkscreen Top")
		(7 "B.SilkS" user "Ref Des/Silkscreen Bottom")
		(1 "F.Mask" user "Board Geometry/Soldermask Top")
		(3 "B.Mask" user "Board Geometry/Soldermask Bottom")
		(17 "Dwgs.User" user "User.Drawings")
		(19 "Cmts.User" user "User.Comments")
		(21 "Eco1.User" user "User.Eco1")
		(23 "Eco2.User" user "User.Eco2")
		(25 "Edge.Cuts" user "Board Geometry/Outline")
		(27 "Margin" user)
		(31 "F.CrtYd" user "Package Geometry/Place Bound Top")
		(29 "B.CrtYd" user "Package Geometry/Place Bound Bottom")
		(35 "F.Fab" user "Ref Des/Assembly Top")
		(33 "B.Fab" user "Ref Des/Assembly Bottom")
	)
	(footprint ""
		(layer "B.Cu")
		(at 29.699458 -152.078436 90)
		(property "Reference" "J9L1"
			(at 2.200148 37.737542 0)
			(unlocked yes)
			(layer "B.SilkS")
			(effects
				(font
					(size 0.7874 0.5842)
					(thickness 0.1524)
				)
				(justify left mirror)
			)
		)
		(property "Value" ""
			(at 0 0 90)
			(layer "B.Fab")
			(effects
				(font
					(size 1.27 1.27)
				)
				(justify mirror)
			)
		)
		(duplicate_pad_numbers_are_jumpers no)
		(pad "199" smd rect
			(at -4.59994 45.900086 270)
			(size 1.8034 0.508)
			(layers "B.Cu" "B.Mask" "B.Paste")
			(net "M_M_ECC<7>")
		)
		(pad "200" smd rect
			(at -4.59994 46.74997 270)
			(size 1.8034 0.508)
			(layers "B.Cu" "B.Mask" "B.Paste")
			(net "GND")
		)
		(pad "201" smd rect
			(at -4.59994 47.600108 270)
			(size 1.8034 0.508)
			(layers "B.Cu" "B.Mask" "B.Paste")
			(net "M_M_ECC<3>")
		)
		(pad "202" smd rect
			(at -4.59994 48.449992 270)
			(size 1.8034 0.508)
			(layers "B.Cu" "B.Mask" "B.Paste")
			(net "GND")
		)
		(pad "203" smd rect
			(at -4.59994 49.299876 270)
			(size 1.8034 0.508)
			(layers "B.Cu" "B.Mask" "B.Paste")
			(net "M_M_CKE<3>")
		)
		(pad "204" smd rect
			(at -4.59994 50.150014 270)
			(size 1.8034 0.508)
			(layers "B.Cu" "B.Mask" "B.Paste")
			(net "PVDDQ_KLM")
		)
		(pad "205" smd rect
			(at -4.59994 50.999898 270)
			(size 1.8034 0.508)
			(layers "B.Cu" "B.Mask" "B.Paste")
			(net "TP_CH_M_DIMM_M1_RFU_0")
		)
		(pad "206" smd rect
			(at -4.59994 51.850036 270)
			(size 1.8034 0.508)
			(layers "B.Cu" "B.Mask" "B.Paste")
			(net "PVDDQ_KLM")
		)
		(pad "207" smd rect
			(at -4.59994 52.69992 270)
			(size 1.8034 0.508)
			(layers "B.Cu" "B.Mask" "B.Paste")
			(net "M_M_BG<1>")
		)
		(pad "208" smd rect
			(at -4.59994 53.550058 270)
			(size 1.8034 0.508)
			(layers "B.Cu" "B.Mask" "B.Paste")
			(net "M_M_ALERT_N")
		)
		(pad "209" smd rect
			(at -4.59994 54.399942 270)
			(size 1.8034 0.508)
			(layers "B.Cu" "B.Mask" "B.Paste")
			(net "PVDDQ_KLM")
		)
		(pad "210" smd rect
			(at -4.59994 55.25008 270)
			(size 1.8034 0.508)
			(layers "B.Cu" "B.Mask" "B.Paste")
			(net "M_M_MA<11>")
		)
		(pad "211" smd rect
			(at -4.59994 56.099964 270)
			(size 1.8034 0.508)
			(layers "B.Cu" "B.Mask" "B.Paste")
			(net "M_M_MA<7>")
		)
		(pad "212" smd rect
			(at -4.59994 56.950102 270)
			(size 1.8034 0.508)
			(layers "B.Cu" "B.Mask" "B.Paste")
			(net "PVDDQ_KLM")
		)
		(pad "213" smd rect
			(at -4.59994 57.799986 270)
			(size 1.8034 0.508)
			(layers "B.Cu" "B.Mask" "B.Paste")
			(net "M_M_MA<5>")
		)
		(pad "214" smd rect
			(at -4.59994 58.650124 270)
			(size 1.8034 0.508)
			(layers "B.Cu" "B.Mask" "B.Paste")
			(net "M_M_MA<4>")
		)
		(pad "215" smd rect
			(at -4.59994 59.500008 270)
			(size 1.8034 0.508)
			(layers "B.Cu" "B.Mask" "B.Paste")
			(net "PVDDQ_KLM")
		)
		(pad "216" smd rect
			(at -4.59994 60.349892 270)
			(size 1.8034 0.508)
			(layers "B.Cu" "B.Mask" "B.Paste")
			(net "M_M_MA<2>")
		)
		(pad "217" smd rect
			(at -4.59994 61.20003 270)
			(size 1.8034 0.508)
			(layers "B.Cu" "B.Mask" "B.Paste")
			(net "PVDDQ_KLM")
		)
		(pad "218" smd rect
			(at -4.59994 62.049914 270)
			(size 1.8034 0.508)
			(layers "B.Cu" "B.Mask" "B.Paste")
			(net "M_M_CLK_DP<3>")
		)
		(pad "219" smd rect
			(at -4.59994 62.900052 270)
			(size 1.8034 0.508)
			(layers "B.Cu" "B.Mask" "B.Paste")
			(net "M_M_CLK_DN<3>")
		)
		(pad "220" smd rect
			(at -4.59994 63.749936 270)
			(size 1.8034 0.508)
			(layers "B.Cu" "B.Mask" "B.Paste")
			(net "PVDDQ_KLM")
		)
		(pad "221" smd rect
			(at -4.59994 64.600074 270)
			(size 1.8034 0.508)
			(layers "B.Cu" "B.Mask" "B.Paste")
			(net "PVTT_KLM")
		)
		(pad "222" smd rect
			(at -4.59994 70.550024 270)
			(size 1.8034 0.508)
			(layers "B.Cu" "B.Mask" "B.Paste")
			(net "M_M_PAR")
		)
		(pad "223" smd rect
			(at -4.59994 71.399908 270)
			(size 1.8034 0.508)
			(layers "B.Cu" "B.Mask" "B.Paste")
			(net "PVDDQ_KLM")
		)
		(pad "224" smd rect
			(at -4.59994 72.250046 270)
			(size 1.8034 0.508)
			(layers "B.Cu" "B.Mask" "B.Paste")
			(net "M_M_BA<1>")
		)
		(pad "225" smd rect
			(at -4.59994 73.09993 270)
			(size 1.8034 0.508)
			(layers "B.Cu" "B.Mask" "B.Paste")
			(net "M_M_MA<10>")
		)
		(pad "226" smd rect
			(at -4.59994 73.950068 270)
			(size 1.8034 0.508)
			(layers "B.Cu" "B.Mask" "B.Paste")
			(net "PVDDQ_KLM")
		)
		(pad "227" smd rect
			(at -4.59994 74.799952 270)
			(size 1.8034 0.508)
			(layers "B.Cu" "B.Mask" "B.Paste")
			(net "TP_CH_M_DIMM_M1_RFU_1")
		)
		(pad "228" smd rect
			(at -4.59994 75.65009 270)
			(size 1.8034 0.508)
			(layers "B.Cu" "B.Mask" "B.Paste")
			(net "M_M_MA<14>")
		)
		(pad "229" smd rect
			(at -4.59994 76.499974 270)
			(size 1.8034 0.508)
			(layers "B.Cu" "B.Mask" "B.Paste")
			(net "PVDDQ_KLM")
		)
		(pad "230" smd rect
			(at -4.59994 77.350112 270)
			(size 1.8034 0.508)
			(layers "B.Cu" "B.Mask" "B.Paste")
			(net "FM_ADR_COMPLETE_KLM_N")
		)
		(pad "231" smd rect
			(at -4.59994 78.199996 270)
			(size 1.8034 0.508)
			(layers "B.Cu" "B.Mask" "B.Paste")
			(net "PVDDQ_KLM")
		)
		(pad "232" smd rect
			(at -4.59994 79.04988 270)
			(size 1.8034 0.508)
			(layers "B.Cu" "B.Mask" "B.Paste")
			(net "M_M_MA<13>")
		)
		(pad "233" smd rect
			(at -4.59994 79.900018 270)
			(size 1.8034 0.508)
			(layers "B.Cu" "B.Mask" "B.Paste")
			(net "PVDDQ_KLM")
		)
		(pad "234" smd rect
			(at -4.59994 80.749902 270)
			(size 1.8034 0.508)
			(layers "B.Cu" "B.Mask" "B.Paste")
			(net "M_M_MA<17>")
		)
		(pad "235" smd rect
			(at -4.59994 81.60004 270)
			(size 1.8034 0.508)
			(layers "B.Cu" "B.Mask" "B.Paste")
			(net "M_M_C<2>")
		)
		(pad "236" smd rect
			(at -4.59994 82.449924 270)
			(size 1.8034 0.508)
			(layers "B.Cu" "B.Mask" "B.Paste")
			(net "PVDDQ_KLM")
		)
		(pad "237" smd rect
			(at -4.59994 83.300062 270)
			(size 1.8034 0.508)
			(layers "B.Cu" "B.Mask" "B.Paste")
			(net "M_M_CS_N<7>")
		)
		(pad "238" smd rect
			(at -4.59994 84.149946 270)
			(size 1.8034 0.508)
			(layers "B.Cu" "B.Mask" "B.Paste")
			(net "PVPP_KLM")
		)
		(pad "239" smd rect
			(at -4.59994 85.000084 270)
			(size 1.8034 0.508)
			(layers "B.Cu" "B.Mask" "B.Paste")
			(net "GND")
		)
		(pad "240" smd rect
			(at -4.59994 85.849968 270)
			(size 1.8034 0.508)
			(layers "B.Cu" "B.Mask" "B.Paste")
			(net "M_M_DQ<37>")
		)
		(pad "241" smd rect
			(at -4.59994 86.700106 270)
			(size 1.8034 0.508)
			(layers "B.Cu" "B.Mask" "B.Paste")
			(net "GND")
		)
		(pad "242" smd rect
			(at -4.59994 87.54999 270)
			(size 1.8034 0.508)
			(layers "B.Cu" "B.Mask" "B.Paste")
			(net "M_M_DQ<33>")
		)
		(pad "243" smd rect
			(at -4.59994 88.399874 270)
			(size 1.8034 0.508)
			(layers "B.Cu" "B.Mask" "B.Paste")
			(net "GND")
		)
		(pad "244" smd rect
			(at -4.59994 89.250012 270)
			(size 1.8034 0.508)
			(layers "B.Cu" "B.Mask" "B.Paste")
			(net "M_M_DQS_DN<4>")
		)
		(pad "245" smd rect
			(at -4.59994 90.099896 270)
			(size 1.8034 0.508)
			(layers "B.Cu" "B.Mask" "B.Paste")
			(net "M_M_DQS_DP<4>")
		)
		(pad "246" smd rect
			(at -4.59994 90.950034 270)
			(size 1.8034 0.508)
			(layers "B.Cu" "B.Mask" "B.Paste")
			(net "GND")
		)
	)
)
